(kicad_pcb
	(version 20241229)
	(generator "pcbnew")
	(generator_version "9.0")
	(general
		(thickness 1.552)
		(legacy_teardrops no)
	)
	(paper "A4")
	(title_block
		(date "2023-07-25")
		(rev "1.1.4")
		(comment 9 "footprints 173-177 of 379")
	)
	(layers
		(0 "F.Cu" signal)
		(4 "In1.Cu" signal)
		(6 "In2.Cu" signal)
		(8 "In3.Cu" signal)
		(10 "In4.Cu" signal)
		(12 "In5.Cu" signal)
		(14 "In6.Cu" signal)
		(2 "B.Cu" signal)
		(9 "F.Adhes" user "F.Adhesive")
		(11 "B.Adhes" user "B.Adhesive")
		(13 "F.Paste" user)
		(15 "B.Paste" user)
		(5 "F.SilkS" user "F.Silkscreen")
		(7 "B.SilkS" user "B.Silkscreen")
		(1 "F.Mask" user)
		(3 "B.Mask" user)
		(17 "Dwgs.User" user "User.Drawings")
		(19 "Cmts.User" user "User.Comments")
		(21 "Eco1.User" user "User.Eco1")
		(23 "Eco2.User" user "User.Eco2")
		(25 "Edge.Cuts" user)
		(27 "Margin" user)
		(31 "F.CrtYd" user "F.Courtyard")
		(29 "B.CrtYd" user "B.Courtyard")
		(35 "F.Fab" user)
		(33 "B.Fab" user)
	)
	(footprint "antmicro-footprints:R_0603_1608Metric"
		(layer "F.Cu")
		(at 157.03 88.65 -90)
		(descr "Resistor SMD 0603")
		(tags "resistor SMD 0603")
		(property "Reference" "R106"
			(at -1.21 -1.9 270)
			(layer "F.SilkS")
			(effects
				(font
					(size 0.65 0.65)
					(thickness 0.15)
				)
				(justify left bottom)
			)
		)
		(property "Value" "R_10k_0603"
			(at 0 1.6 270)
			(layer "F.Fab")
			(hide yes)
			(effects
				(font
					(size 0.7 0.7)
					(thickness 0.15)
				)
				(justify left bottom)
			)
		)
		(property "Datasheet" "https://www.bourns.com/docs/product-datasheets/cr.pdf"
			(at 0 0 270)
			(layer "F.Fab")
			(hide yes)
			(effects
				(font
					(size 1.27 1.27)
					(thickness 0.15)
				)
			)
		)
		(property "Description" "SMD Chip Resistor, 10 kohm, ± 1%, 100 mW, 0603 [1608 Metric], Thick Film, General Purpose"
			(at 0 0 270)
			(layer "F.Fab")
			(hide yes)
			(effects
				(font
					(size 1.27 1.27)
					(thickness 0.15)
				)
			)
		)
		(property "Author" "Antmicro"
			(at 68.38 245.68 0)
			(layer "F.Fab")
			(hide yes)
			(effects
				(font
					(size 1 1)
					(thickness 0.15)
				)
			)
		)
		(property "License" "Apache-2.0"
			(at 68.38 245.68 0)
			(layer "F.Fab")
			(hide yes)
			(effects
				(font
					(size 1 1)
					(thickness 0.15)
				)
			)
		)
		(property "MPN" "CR0603-FX-1002ELF"
			(at 68.38 245.68 0)
			(layer "F.Fab")
			(hide yes)
			(effects
				(font
					(size 1 1)
					(thickness 0.15)
				)
			)
		)
		(property "Manufacturer" "Bourns"
			(at 68.38 245.68 0)
			(layer "F.Fab")
			(hide yes)
			(effects
				(font
					(size 1 1)
					(thickness 0.15)
				)
			)
		)
		(property "Tolerance" "1%"
			(at 68.38 245.68 0)
			(layer "F.Fab")
			(hide yes)
			(effects
				(font
					(size 1 1)
					(thickness 0.15)
				)
			)
		)
		(property "Val" "10k"
			(at 68.38 245.68 0)
			(layer "F.Fab")
			(hide yes)
			(effects
				(font
					(size 1 1)
					(thickness 0.15)
				)
			)
		)
		(sheetname "/Peripherals/")
		(sheetfile "peripherals.kicad_sch")
		(attr smd exclude_from_pos_files exclude_from_bom dnp)
		(fp_line
			(start -0.15 0.4)
			(end 0.15 0.4)
			(stroke
				(width 0.15)
				(type solid)
			)
			(layer "F.SilkS")
		)
		(fp_line
			(start -0.15 -0.4)
			(end 0.15 -0.4)
			(stroke
				(width 0.15)
				(type solid)
			)
			(layer "F.SilkS")
		)
		(fp_rect
			(start -1.25 -0.65)
			(end 1.25 0.65)
			(stroke
				(width 0.05)
				(type solid)
			)
			(fill no)
			(layer "F.CrtYd")
		)
		(fp_rect
			(start -0.8 -0.4)
			(end 0.8 0.4)
			(stroke
				(width 0.15)
				(type solid)
			)
			(fill no)
			(layer "F.Fab")
		)
		(fp_text user "${REFERENCE}"
			(at -1.25 3.898 270)
			(layer "F.Fab")
			(effects
				(font
					(size 0.7 0.7)
					(thickness 0.15)
				)
				(justify left bottom)
			)
		)
		(fp_text user "License: Apache-2.0"
			(at -1.25 5.9 270)
			(layer "F.Fab")
			(effects
				(font
					(size 0.7 0.7)
					(thickness 0.15)
				)
				(justify left bottom)
			)
		)
		(fp_text user "Author: Antmicro"
			(at -1.25 4.9 270)
			(layer "F.Fab")
			(effects
				(font
					(size 0.7 0.7)
					(thickness 0.15)
				)
				(justify left bottom)
			)
		)
		(pad "1" smd roundrect
			(at -0.7 0 270)
			(size 0.8 1)
			(layers "F.Cu" "F.Mask" "F.Paste")
			(roundrect_rratio 0.2)
			(net 307 "/Peripherals/FFC1_PEN")
			(pintype "passive")
		)
		(pad "2" smd roundrect
			(at 0.7 0 270)
			(size 0.8 1)
			(layers "F.Cu" "F.Mask" "F.Paste")
			(roundrect_rratio 0.2)
			(net 1 "GND")
			(pintype "passive")
		)
	)
	(footprint "antmicro-footprints:TP_SMD_0.75mm"
		(layer "F.Cu")
		(at 158.3 93.65)
		(property "Reference" "TP44"
			(at -1.37 1.39 0)
			(layer "F.SilkS")
			(effects
				(font
					(size 0.65 0.65)
					(thickness 0.15)
				)
				(justify left bottom)
			)
		)
		(property "Value" "TP_0.75mm_SMD"
			(at 0 1.2 0)
			(layer "F.Fab")
			(hide yes)
			(effects
				(font
					(size 0.7 0.7)
					(thickness 0.15)
				)
				(justify left bottom)
			)
		)
		(property "Description" "SMT test point"
			(at 0 0 0)
			(layer "F.Fab")
			(hide yes)
			(effects
				(font
					(size 1.27 1.27)
					(thickness 0.15)
				)
			)
		)
		(property "Author" "Antmicro"
			(at 0 0 0)
			(layer "F.Fab")
			(hide yes)
			(effects
				(font
					(size 1 1)
					(thickness 0.15)
				)
			)
		)
		(property "License" "Apache-2.0"
			(at 0 0 0)
			(layer "F.Fab")
			(hide yes)
			(effects
				(font
					(size 1 1)
					(thickness 0.15)
				)
			)
		)
		(property "MPN" ""
			(at 0 0 0)
			(layer "F.Fab")
			(hide yes)
			(effects
				(font
					(size 1 1)
					(thickness 0.15)
				)
			)
		)
		(property "Manufacturer" ""
			(at 0 0 0)
			(layer "F.Fab")
			(hide yes)
			(effects
				(font
					(size 1 1)
					(thickness 0.15)
				)
			)
		)
		(sheetname "/Peripherals/")
		(sheetfile "peripherals.kicad_sch")
		(attr exclude_from_pos_files)
		(fp_circle
			(center 0 0)
			(end 0.475 0)
			(stroke
				(width 0.05)
				(type default)
			)
			(fill no)
			(layer "F.CrtYd")
		)
		(fp_text user "Author: Antmicro"
			(at -0.4 3.901 0)
			(layer "F.Fab")
			(effects
				(font
					(size 0.7 0.7)
					(thickness 0.15)
				)
				(justify left bottom)
			)
		)
		(fp_text user "License: Apache-2.0"
			(at -0.4 5.101 0)
			(layer "F.Fab")
			(effects
				(font
					(size 0.7 0.7)
					(thickness 0.15)
				)
				(justify left bottom)
			)
		)
		(fp_text user "${REFERENCE}"
			(at -0.4 2.7 0)
			(layer "F.Fab")
			(effects
				(font
					(size 0.7 0.7)
					(thickness 0.15)
				)
				(justify left bottom)
			)
		)
		(pad "1" smd circle
			(at 0 0)
			(size 0.75 0.75)
			(layers "F.Cu" "F.Mask")
			(net 351 "Net-(U13-~{FAULT})")
			(pinfunction "1")
			(pintype "passive")
		)
	)
	(footprint "antmicro-footprints:R_0603_1608Metric"
		(layer "F.Cu")
		(at 106.09 107.2 -90)
		(descr "Resistor SMD 0603")
		(tags "resistor SMD 0603")
		(property "Reference" "R58"
			(at 1.24 -0.34 90)
			(layer "F.SilkS")
			(effects
				(font
					(size 0.65 0.65)
					(thickness 0.15)
				)
				(justify right bottom)
			)
		)
		(property "Value" "R_0R_0603"
			(at 0 1.6 90)
			(layer "F.Fab")
			(hide yes)
			(effects
				(font
					(size 0.7 0.7)
					(thickness 0.15)
				)
				(justify right bottom)
			)
		)
		(property "Datasheet" "https://www.bourns.com/docs/product-datasheets/cr.pdf?sfvrsn=574d41f6_14"
			(at 0 0 270)
			(layer "F.Fab")
			(hide yes)
			(effects
				(font
					(size 1.27 1.27)
					(thickness 0.15)
				)
			)
		)
		(property "Description" "Zero Ohm Resistor, Jumper, 0603 [1608 Metric], Thick Film, 100 mW, 1 A, Surface Mount Device, CR"
			(at 0 0 270)
			(layer "F.Fab")
			(hide yes)
			(effects
				(font
					(size 1.27 1.27)
					(thickness 0.15)
				)
			)
		)
		(property "Author" "Antmicro"
			(at -1.11 213.29 0)
			(layer "F.Fab")
			(hide yes)
			(effects
				(font
					(size 1 1)
					(thickness 0.15)
				)
			)
		)
		(property "Current" "1A"
			(at -1.11 213.29 0)
			(layer "F.Fab")
			(hide yes)
			(effects
				(font
					(size 1 1)
					(thickness 0.15)
				)
			)
		)
		(property "License" "Apache-2.0"
			(at -1.11 213.29 0)
			(layer "F.Fab")
			(hide yes)
			(effects
				(font
					(size 1 1)
					(thickness 0.15)
				)
			)
		)
		(property "MPN" "CR0603-J/-000ELF"
			(at -1.11 213.29 0)
			(layer "F.Fab")
			(hide yes)
			(effects
				(font
					(size 1 1)
					(thickness 0.15)
				)
			)
		)
		(property "Manufacturer" "Bourns"
			(at -1.11 213.29 0)
			(layer "F.Fab")
			(hide yes)
			(effects
				(font
					(size 1 1)
					(thickness 0.15)
				)
			)
		)
		(property "Tolerance" "~"
			(at -1.11 213.29 0)
			(layer "F.Fab")
			(hide yes)
			(effects
				(font
					(size 1 1)
					(thickness 0.15)
				)
			)
		)
		(property "Val" "0R"
			(at -1.11 213.29 0)
			(layer "F.Fab")
			(hide yes)
			(effects
				(font
					(size 1 1)
					(thickness 0.15)
				)
			)
		)
		(sheetname "/FPGA/")
		(sheetfile "fpga.kicad_sch")
		(attr smd)
		(fp_line
			(start -0.15 0.4)
			(end 0.15 0.4)
			(stroke
				(width 0.15)
				(type solid)
			)
			(layer "F.SilkS")
		)
		(fp_line
			(start -0.15 -0.4)
			(end 0.15 -0.4)
			(stroke
				(width 0.15)
				(type solid)
			)
			(layer "F.SilkS")
		)
		(fp_rect
			(start -1.25 -0.65)
			(end 1.25 0.65)
			(stroke
				(width 0.05)
				(type solid)
			)
			(fill no)
			(layer "F.CrtYd")
		)
		(fp_rect
			(start -0.8 -0.4)
			(end 0.8 0.4)
			(stroke
				(width 0.15)
				(type solid)
			)
			(fill no)
			(layer "F.Fab")
		)
		(fp_text user "License: Apache-2.0"
			(at -1.25 5.9 270)
			(layer "F.Fab")
			(effects
				(font
					(size 0.7 0.7)
					(thickness 0.15)
				)
				(justify left bottom)
			)
		)
		(fp_text user "${REFERENCE}"
			(at -1.25 3.898 270)
			(layer "F.Fab")
			(effects
				(font
					(size 0.7 0.7)
					(thickness 0.15)
				)
				(justify left bottom)
			)
		)
		(fp_text user "Author: Antmicro"
			(at -1.25 4.9 270)
			(layer "F.Fab")
			(effects
				(font
					(size 0.7 0.7)
					(thickness 0.15)
				)
				(justify left bottom)
			)
		)
		(pad "1" smd roundrect
			(at -0.7 0 270)
			(size 0.8 1)
			(layers "F.Cu" "F.Mask" "F.Paste")
			(roundrect_rratio 0.2)
			(net 290 "Net-(U17-SDA)")
			(pintype "passive")
		)
		(pad "2" smd roundrect
			(at 0.7 0 270)
			(size 0.8 1)
			(layers "F.Cu" "F.Mask" "F.Paste")
			(roundrect_rratio 0.2)
			(net 101 "SDA")
			(pintype "passive")
		)
	)
	(footprint "antmicro-footprints:L_Coilcraft-XEL4030"
		(layer "F.Cu")
		(at 164.39 62 180)
		(property "Reference" "L3"
			(at -2.44 -1.04 180)
			(layer "F.SilkS")
			(effects
				(font
					(size 0.65 0.65)
					(thickness 0.15)
				)
				(justify left bottom)
			)
		)
		(property "Value" "L_3u3_5.9A_XEL4030"
			(at 0 3.35 180)
			(layer "F.Fab")
			(hide yes)
			(effects
				(font
					(size 0.7 0.7)
					(thickness 0.15)
				)
				(justify left bottom)
			)
		)
		(property "Datasheet" "https://www.coilcraft.com/getmedia/8245f050-f190-4295-8c41-7c03d662ee3d/xel4030.pdf"
			(at 0 0 180)
			(layer "F.Fab")
			(hide yes)
			(effects
				(font
					(size 1.27 1.27)
					(thickness 0.15)
				)
			)
		)
		(property "Description" "Power Inductor (SMT), AEC-Q200, 3.3 µH, 6.6 A, Shielded, 5.9 A, XEL4030"
			(at 0 0 180)
			(layer "F.Fab")
			(hide yes)
			(effects
				(font
					(size 1.27 1.27)
					(thickness 0.15)
				)
			)
		)
		(property "Author" "Antmicro"
			(at 328.78 124 0)
			(layer "F.Fab")
			(hide yes)
			(effects
				(font
					(size 1 1)
					(thickness 0.15)
				)
			)
		)
		(property "IMax" "6.6 A"
			(at 328.78 124 0)
			(layer "F.Fab")
			(hide yes)
			(effects
				(font
					(size 1 1)
					(thickness 0.15)
				)
			)
		)
		(property "ISat" "5.9 A"
			(at 328.78 124 0)
			(layer "F.Fab")
			(hide yes)
			(effects
				(font
					(size 1 1)
					(thickness 0.15)
				)
			)
		)
		(property "License" "Apache-2.0"
			(at 328.78 124 0)
			(layer "F.Fab")
			(hide yes)
			(effects
				(font
					(size 1 1)
					(thickness 0.15)
				)
			)
		)
		(property "MPN" "XEL4030-332MEC"
			(at 328.78 124 0)
			(layer "F.Fab")
			(hide yes)
			(effects
				(font
					(size 1 1)
					(thickness 0.15)
				)
			)
		)
		(property "Manufacturer" "Coilcraft"
			(at 328.78 124 0)
			(layer "F.Fab")
			(hide yes)
			(effects
				(font
					(size 1 1)
					(thickness 0.15)
				)
			)
		)
		(property "Size" "4.0x4.0"
			(at 328.78 124 0)
			(layer "F.Fab")
			(hide yes)
			(effects
				(font
					(size 1 1)
					(thickness 0.15)
				)
			)
		)
		(property "Val" "3u3/6.6A"
			(at 328.78 124 0)
			(layer "F.Fab")
			(hide yes)
			(effects
				(font
					(size 1 1)
					(thickness 0.15)
				)
			)
		)
		(sheetname "/Power Supply/")
		(sheetfile "supply.kicad_sch")
		(attr smd)
		(fp_line
			(start 2.2 2.2)
			(end 2.2 -2.2)
			(stroke
				(width 0.15)
				(type solid)
			)
			(layer "F.SilkS")
		)
		(fp_line
			(start -2.2 2.2)
			(end 2.2 2.2)
			(stroke
				(width 0.15)
				(type solid)
			)
			(layer "F.SilkS")
		)
		(fp_line
			(start -2.2 2.2)
			(end -2.2 -2.2)
			(stroke
				(width 0.15)
				(type solid)
			)
			(layer "F.SilkS")
		)
		(fp_line
			(start -2.2 -2.2)
			(end 2.2 -2.2)
			(stroke
				(width 0.15)
				(type solid)
			)
			(layer "F.SilkS")
		)
		(fp_rect
			(start -2.4 -2.4)
			(end 2.4 2.4)
			(stroke
				(width 0.05)
				(type solid)
			)
			(fill no)
			(layer "F.CrtYd")
		)
		(fp_rect
			(start -2.15 -2.15)
			(end 2.15 2.15)
			(stroke
				(width 0.15)
				(type solid)
			)
			(fill no)
			(layer "F.Fab")
		)
		(fp_text user "Author: Antmicro"
			(at -2.4 5.35 180)
			(layer "F.Fab")
			(effects
				(font
					(size 0.7 0.7)
					(thickness 0.15)
				)
				(justify left bottom)
			)
		)
		(fp_text user "${REFERENCE}"
			(at -2.4 6.55 180)
			(layer "F.Fab")
			(effects
				(font
					(size 0.7 0.7)
					(thickness 0.15)
				)
				(justify left bottom)
			)
		)
		(fp_text user "License: Apache-2.0"
			(at -2.4 7.75 180)
			(layer "F.Fab")
			(effects
				(font
					(size 0.7 0.7)
					(thickness 0.15)
				)
				(justify left bottom)
			)
		)
		(pad "1" smd roundrect
			(at -1.185 0 180)
			(size 0.98 3.4)
			(layers "F.Cu" "F.Mask" "F.Paste")
			(roundrect_rratio 0.1)
			(net 278 "/Power Supply/3V3_SW")
			(pintype "passive")
		)
		(pad "2" smd roundrect
			(at 1.185 0 180)
			(size 0.98 3.4)
			(layers "F.Cu" "F.Mask" "F.Paste")
			(roundrect_rratio 0.1)
			(net 275 "/Power Supply/3V3_OUT")
			(pintype "passive")
		)
	)
	(footprint "antmicro-footprints:R_0603_1608Metric"
		(layer "F.Cu")
		(at 158.29 81.2)
		(descr "Resistor SMD 0603")
		(tags "resistor SMD 0603")
		(property "Reference" "R114"
			(at -4.06 0.54 0)
			(layer "F.SilkS")
			(effects
				(font
					(size 0.65 0.65)
					(thickness 0.15)
				)
				(justify left bottom)
			)
		)
		(property "Value" "R_10k_0603"
			(at 0 1.6 0)
			(layer "F.Fab")
			(hide yes)
			(effects
				(font
					(size 0.7 0.7)
					(thickness 0.15)
				)
				(justify left bottom)
			)
		)
		(property "Datasheet" "https://www.bourns.com/docs/product-datasheets/cr.pdf"
			(at 0 0 0)
			(layer "F.Fab")
			(hide yes)
			(effects
				(font
					(size 1.27 1.27)
					(thickness 0.15)
				)
			)
		)
		(property "Description" "SMD Chip Resistor, 10 kohm, ± 1%, 100 mW, 0603 [1608 Metric], Thick Film, General Purpose"
			(at 0 0 0)
			(layer "F.Fab")
			(hide yes)
			(effects
				(font
					(size 1.27 1.27)
					(thickness 0.15)
				)
			)
		)
		(property "Author" "Antmicro"
			(at 0 0 0)
			(layer "F.Fab")
			(hide yes)
			(effects
				(font
					(size 1 1)
					(thickness 0.15)
				)
			)
		)
		(property "License" "Apache-2.0"
			(at 0 0 0)
			(layer "F.Fab")
			(hide yes)
			(effects
				(font
					(size 1 1)
					(thickness 0.15)
				)
			)
		)
		(property "MPN" "CR0603-FX-1002ELF"
			(at 0 0 0)
			(layer "F.Fab")
			(hide yes)
			(effects
				(font
					(size 1 1)
					(thickness 0.15)
				)
			)
		)
		(property "Manufacturer" "Bourns"
			(at 0 0 0)
			(layer "F.Fab")
			(hide yes)
			(effects
				(font
					(size 1 1)
					(thickness 0.15)
				)
			)
		)
		(property "Tolerance" "1%"
			(at 0 0 0)
			(layer "F.Fab")
			(hide yes)
			(effects
				(font
					(size 1 1)
					(thickness 0.15)
				)
			)
		)
		(property "Val" "10k"
			(at 0 0 0)
			(layer "F.Fab")
			(hide yes)
			(effects
				(font
					(size 1 1)
					(thickness 0.15)
				)
			)
		)
		(sheetname "/Peripherals/")
		(sheetfile "peripherals.kicad_sch")
		(attr smd)
		(fp_line
			(start -0.15 -0.4)
			(end 0.15 -0.4)
			(stroke
				(width 0.15)
				(type solid)
			)
			(layer "F.SilkS")
		)
		(fp_line
			(start -0.15 0.4)
			(end 0.15 0.4)
			(stroke
				(width 0.15)
				(type solid)
			)
			(layer "F.SilkS")
		)
		(fp_rect
			(start -1.25 -0.65)
			(end 1.25 0.65)
			(stroke
				(width 0.05)
				(type solid)
			)
			(fill no)
			(layer "F.CrtYd")
		)
		(fp_rect
			(start -0.8 -0.4)
			(end 0.8 0.4)
			(stroke
				(width 0.15)
				(type solid)
			)
			(fill no)
			(layer "F.Fab")
		)
		(fp_text user "License: Apache-2.0"
			(at -1.25 5.9 0)
			(layer "F.Fab")
			(effects
				(font
					(size 0.7 0.7)
					(thickness 0.15)
				)
				(justify left bottom)
			)
		)
		(fp_text user "${REFERENCE}"
			(at -1.25 3.898 0)
			(layer "F.Fab")
			(effects
				(font
					(size 0.7 0.7)
					(thickness 0.15)
				)
				(justify left bottom)
			)
		)
		(fp_text user "Author: Antmicro"
			(at -1.25 4.9 0)
			(layer "F.Fab")
			(effects
				(font
					(size 0.7 0.7)
					(thickness 0.15)
				)
				(justify left bottom)
			)
		)
		(pad "1" smd roundrect
			(at -0.7 0)
			(size 0.8 1)
			(layers "F.Cu" "F.Mask" "F.Paste")
			(roundrect_rratio 0.2)
			(net 2 "+3V3")
			(pintype "passive")
		)
		(pad "2" smd roundrect
			(at 0.7 0)
			(size 0.8 1)
			(layers "F.Cu" "F.Mask" "F.Paste")
			(roundrect_rratio 0.2)
			(net 315 "/Peripherals/QWIIC_PEN")
			(pintype "passive")
		)
	)
)
